# Wiwynn_Honey Badger_Panther Plus MB_12L_Stackup_20150121.xlsx — Wiwynn (pcb-stackup)
|  |  |  |  |  |  |  |  |  |  | Single Ended Type(mil) |  |  |  |  |  |  |  |  |  |  |  |  |  |  |  |  | Differential Type(mil) |  |  |  |  |  |  |  |  |  |  |  |
|  |  |  |  |  |  |  |  |  | Imp | 33 |  |  |  | 38 |  |  |  | 40 |  |  |  | 50 |  |  |  | Imp | 65 |  |  |  |  |  | 85 |  |  |  |  |  |
|  |  |  |  |  |  |  |  |  | Variation | Inner /Outer ±5Ω |  |  |  | Inner /Outer ±5Ω |  |  |  | Inner /Outer ±5Ω |  |  |  | Inner /Outer ±5Ω |  |  |  | Variation | Inner 10% / Outer 10% |  |  |  |  |  | Inner 10% / Outer 10% |  |  |  |  |  |
|  |  |  |  |  |  |  |  |  | Bus | DDR CMD/Address |  |  |  | DDR Contrl/DQ/Strobe/Clk |  |  |  | DDR Contrl/DQ/Strobe/CLK |  |  |  | MISC./VGA |  |  |  | Bus | DDR CLK |  |  |  |  |  | PCIe/USB/SATA/SGMII/RGMII |  |  |  |  |  |
|  |  |  |  |  |  |  |  |  | Type | SE |  |  |  | SE |  |  |  | SE |  |  |  | SE |  |  |  | Type | DP |  |  |  |  |  | DP |  |  |  |  |  |
| Layer |  |  | Thickness |  | Glass style | Er |  | Df(1G) | Layers | All |  |  |  | All |  |  |  | All |  |  |  | All |  |  |  | Layers | All |  |  |  |  |  | All |  |  |  |  |  |
|  |  | Cu oz | Wiwynn | Vender |  | Wiwynn | Vender |  |  | Wiwynn |  | Vender |  | Wiwynn |  | Vender |  | Wiwynn |  | Vender |  | Wiwynn |  | Vender |  |  | Wiwynn |  |  | Vender |  |  | Wiwynn |  |  | Vender |  |  |
|  | Mask |  | 0.5 |  |  | 3.8 |  |  |  | Width | Imp | Width | Imp | Width | Imp | Width | Imp | Width | Imp | Width | Imp | Width | Imp | Width | Imp |  | Width | Space | Imp | Width | Space | Imp | Width | Space | Imp | Width | Space | Imp |
| Top | Signal | 0.5 oz + plating | 1.9 |  |  |  |  |  | S1 | 9.5 |  |  |  | 7.5 |  |  |  | 7 |  |  |  | 4.5 |  |  |  | S1 | 8.5 | 6 |  |  |  |  | 5.5 | 8 |  |  |  |  |
|  | Prepreg |  | 2.7 |  |  | 4 |  |  |  |  |  |  |  |  |  |  |  |  |  |  |  |  |  |  |  |  |  |  |  |  |  |  |  |  |  |  |  |  |
| L2 | GND | 1 oz | 1.3 |  |  |  |  |  | G2 | Reference layer |  | Reference layer |  | Reference layer |  | Reference layer |  | Reference layer |  | Reference layer |  | Reference layer |  | Reference layer |  | G2 | Reference layer |  |  | Reference layer |  |  | Reference layer |  |  | Reference layer |  |  |
|  | Core |  | 4 |  |  | 4 |  |  |  |  |  |  |  |  |  |  |  |  |  |  |  |  |  |  |  |  |  |  |  |  |  |  |  |  |  |  |  |  |
| L3 | Signal | 1 oz | 1.3 |  |  |  |  |  | S3 | 7.5 |  |  |  | 6 |  |  |  | 5.5 |  |  |  | 3.5 |  |  |  | S3 | 7.5 | 9 |  |  |  |  | 4.5 | 8.5 |  |  |  |  |
|  | Prepreg |  | 4 |  |  | 4 |  |  |  |  |  |  |  |  |  |  |  |  |  |  |  |  |  |  |  |  |  |  |  |  |  |  |  |  |  |  |  |  |
| L4 | GND | 1 oz | 1.3 |  |  |  |  |  | G4 | Reference layer |  | Reference layer |  | Reference layer |  | Reference layer |  | Reference layer |  | Reference layer |  | Reference layer |  | Reference layer |  | G4 | Reference layer |  |  | Reference layer |  |  | Reference layer |  |  | Reference layer |  |  |
|  | Core |  | 4 |  |  | 4 |  |  |  |  |  |  |  |  |  |  |  |  |  |  |  |  |  |  |  |  |  |  |  |  |  |  |  |  |  |  |  |  |
| L5 | Signal | 1 oz | 1.3 |  |  |  |  |  | S5 | 7.5 |  |  |  | 6 |  |  |  | 5.5 |  |  |  | 3.5 |  |  |  | S5 | 7.5 | 9 |  |  |  |  | 4.5 | 8.5 |  |  |  |  |
|  | Prepreg |  | 4 |  |  | 4 |  |  |  |  |  |  |  |  |  |  |  |  |  |  |  |  |  |  |  |  |  |  |  |  |  |  |  |  |  |  |  |  |
| L6 | PWR | 1 | 1.3 |  |  |  |  |  | P6 | Reference layer |  | Reference layer |  | Reference layer |  | Reference layer |  | Reference layer |  | Reference layer |  | Reference layer |  | Reference layer |  | P6 | Reference layer |  |  | Reference layer |  |  | Reference layer |  |  | Reference layer |  |  |
|  | Core |  | 7 |  |  | 4.2 |  |  |  |  |  |  |  |  |  |  |  |  |  |  |  |  |  |  |  |  |  |  |  |  |  |  |  |  |  |  |  |  |
| L7 | PWR | 1 | 1.3 |  |  |  |  |  | P7 | Reference layer |  | Reference layer |  | Reference layer |  | Reference layer |  | Reference layer |  | Reference layer |  | Reference layer |  | Reference layer |  | P7 | Reference layer |  |  | Reference layer |  |  | Reference layer |  |  | Reference layer |  |  |
|  | Prepreg |  | 4 |  |  | 4 |  |  |  |  |  |  |  |  |  |  |  |  |  |  |  |  |  |  |  |  |  |  |  |  |  |  |  |  |  |  |  |  |
| L8 | Signal | 1 | 1.3 |  |  |  |  |  | S8 | 7.5 |  |  |  | 6 |  |  |  | 5.5 |  |  |  | 3.5 |  |  |  | S8 | 7.5 | 9 |  |  |  |  | 4.5 | 8.5 |  |  |  |  |
|  | Core |  | 4 |  |  | 4 |  |  |  |  |  |  |  |  |  |  |  |  |  |  |  |  |  |  |  |  |  |  |  |  |  |  |  |  |  |  |  |  |
| L9 | GND | 1 | 1.3 |  |  |  |  |  | G9 | Reference layer |  | Reference layer |  | Reference layer |  | Reference layer |  | Reference layer |  | Reference layer |  | Reference layer |  | Reference layer |  | G9 | Reference layer |  |  | Reference layer |  |  | Reference layer |  |  | Reference layer |  |  |
|  | Prepreg |  | 4 |  |  | 4 |  |  |  |  |  |  |  |  |  |  |  |  |  |  |  |  |  |  |  |  |  |  |  |  |  |  |  |  |  |  |  |  |
| L10 | Signal | 1 oz | 1.3 |  |  |  |  |  | S10 | 7.5 |  |  |  | 6 |  |  |  | 5.5 |  |  |  | 3.5 |  |  |  | S10 | 7.5 | 9 |  |  |  |  | 4.5 | 8.5 |  |  |  |  |
|  | Core |  | 4 |  |  | 4 |  |  |  |  |  |  |  |  |  |  |  |  |  |  |  |  |  |  |  |  |  |  |  |  |  |  |  |  |  |  |  |  |
| L11 | GND | 1 oz | 1.3 |  |  |  |  |  | G11 | Reference layer |  | Reference layer |  | Reference layer |  | Reference layer |  | Reference layer |  | Reference layer |  | Reference layer |  | Reference layer |  | G11 | Reference layer |  |  | Reference layer |  |  | Reference layer |  |  | Reference layer |  |  |
|  | Prepreg |  | 2.7 |  |  | 4 |  |  |  |  |  |  |  |  |  |  |  |  |  |  |  |  |  |  |  |  |  |  |  |  |  |  |  |  |  |  |  |  |
| Bottom | Signal | 0.5 oz + plating | 1.9 |  |  |  |  |  | S12 | 9.5 |  |  |  | 7.5 |  |  |  | 7 |  |  |  | 4.5 |  |  |  | S12 | 8.5 | 6 |  |  |  |  | 5.5 | 8 |  |  |  |  |
|  | Mask |  | 0.5 |  |  | 3.8 |  |  |  |  |  |  |  |  |  |  |  |  |  |  |  |  |  |  |  |  |  |  |  |  |  |  |  |  |  |  |  |  |
| Thickness requirement: 1.58±10% mm |  | mil | 62.199999999999989 |  | +/-10% |  |  |  |  |  |  |  |  |  |  |  |  |  |  |  |  |  |  |  |  |  |  |  |  |  |  |  |  |  |  |  |  |  |
|  |  | mm | 1.5798831597663194 |  |  |  |  |  |  |  |  |  |  |  |  |  |  |  |  |  |  |  |  |  |  |  |  |  |  |  |  |  |  |  |  |  |  |  |
